(kicad_pcb
	(version 20260206)
	(generator "pcbnew")
	(generator_version "10.0")
	(general
		(thickness 1.6)
		(legacy_teardrops no)
	)
	(paper "A4")
	(title_block
		(title "9054_F0T_PDB_BD_GPU_F_V04_1213_1550_OCP.brd")
		(comment 1 "Grand Teton / footprints 418-422 of 608")
	)
	(layers
		(0 "F.Cu" signal "TOP")
		(4 "In1.Cu" signal "GND")
		(6 "In2.Cu" signal "IN1")
		(8 "In3.Cu" signal "GND1")
		(10 "In4.Cu" signal "VCC")
		(12 "In5.Cu" signal "VCC1")
		(14 "In6.Cu" signal "GND2")
		(16 "In7.Cu" signal "IN2")
		(18 "In8.Cu" signal "GND3")
		(2 "B.Cu" signal "BOTTOM")
		(9 "F.Adhes" user "F.Adhesive")
		(11 "B.Adhes" user "B.Adhesive")
		(13 "F.Paste" user "Package Geometry/Pastemask Top")
		(15 "B.Paste" user "Package Geometry/Pastemask Bottom")
		(5 "F.SilkS" user "Ref Des/Silkscreen Top")
		(7 "B.SilkS" user "Ref Des/Silkscreen Bottom")
		(1 "F.Mask" user "Board Geometry/Soldermask Top")
		(3 "B.Mask" user "Board Geometry/Soldermask Bottom")
		(17 "Dwgs.User" user "User.Drawings")
		(19 "Cmts.User" user "User.Comments")
		(21 "Eco1.User" user "User.Eco1")
		(23 "Eco2.User" user "User.Eco2")
		(25 "Edge.Cuts" user "Board Geometry/Outline")
		(27 "Margin" user)
		(31 "F.CrtYd" user "Package Geometry/Place Bound Top")
		(29 "B.CrtYd" user "Package Geometry/Place Bound Bottom")
		(35 "F.Fab" user "Ref Des/Assembly Top")
		(33 "B.Fab" user "Ref Des/Assembly Bottom")
	)
	(footprint ""
		(layer "B.Cu")
		(at 436.3085 -152.304496)
		(property "Reference" ""
			(at 0 0 0)
			(layer "B.SilkS")
			(hide yes)
			(effects
				(font
					(size 1.27 1.27)
				)
				(justify mirror)
			)
		)
		(property "Value" ""
			(at 0 0 0)
			(layer "B.Fab")
			(effects
				(font
					(size 1.27 1.27)
				)
				(justify mirror)
			)
		)
		(duplicate_pad_numbers_are_jumpers no)
		(pad "1" smd circle
			(at 0 0 180)
			(size 0.9906 0.9906)
			(layers "B.Cu" "B.Mask" "B.Paste")
			(net "Net_244")
		)
		(zone
			(layer "B.Cu")
			(hatch none 0.5)
			(connect_pads
				(clearance 0)
			)
			(min_thickness 0.25)
			(keepout
				(tracks not_allowed)
				(vias allowed)
				(pads allowed)
				(copperpour not_allowed)
				(footprints allowed)
			)
			(placement
				(enabled no)
				(sheetname "")
			)
			(fill
				(thermal_gap 0.5)
				(thermal_bridge_width 0.5)
				(island_removal_mode 0)
			)
			(polygon
				(pts
					(arc
						(start 437.9341 -152.304496)
						(mid 434.6829 -152.304496)
						(end 437.9341 -152.304496)
					)
				)
			)
		)
	)
	(footprint ""
		(layer "B.Cu")
		(at 277.3934 -71.882)
		(property "Reference" "PR6934"
			(at 0 0 0)
			(layer "B.SilkS")
			(hide yes)
			(effects
				(font
					(size 1.27 1.27)
				)
				(justify mirror)
			)
		)
		(property "Value" ""
			(at 0 0 0)
			(layer "B.Fab")
			(effects
				(font
					(size 1.27 1.27)
				)
				(justify mirror)
			)
		)
		(duplicate_pad_numbers_are_jumpers no)
		(fp_line
			(start -0.7874 -0.4064)
			(end -0.7874 0.4064)
			(stroke
				(width 0.1524)
				(type default)
			)
			(layer "B.SilkS")
		)
		(fp_line
			(start -0.7874 0.4064)
			(end 0.7874 0.4064)
			(stroke
				(width 0.1524)
				(type default)
			)
			(layer "B.SilkS")
		)
		(fp_line
			(start 0.7874 -0.4064)
			(end -0.7874 -0.4064)
			(stroke
				(width 0.1524)
				(type default)
			)
			(layer "B.SilkS")
		)
		(fp_line
			(start 0.7874 0.4064)
			(end 0.7874 -0.4064)
			(stroke
				(width 0.1524)
				(type default)
			)
			(layer "B.SilkS")
		)
		(fp_line
			(start -0.67945 -0.3048)
			(end -0.67945 0.3048)
			(stroke
				(width 0.1)
				(type default)
			)
			(layer "B.Fab")
		)
		(fp_line
			(start -0.67945 0.3048)
			(end -0.120396 0.3048)
			(stroke
				(width 0.1)
				(type default)
			)
			(layer "B.Fab")
		)
		(fp_line
			(start -0.12065 -0.3048)
			(end -0.67945 -0.3048)
			(stroke
				(width 0.1)
				(type default)
			)
			(layer "B.Fab")
		)
		(fp_line
			(start -0.12065 -0.2794)
			(end -0.12065 -0.3048)
			(stroke
				(width 0.1)
				(type default)
			)
			(layer "B.Fab")
		)
		(fp_line
			(start -0.120396 0.2794)
			(end 0.12065 0.2794)
			(stroke
				(width 0.1)
				(type default)
			)
			(layer "B.Fab")
		)
		(fp_line
			(start -0.120396 0.3048)
			(end -0.120396 0.2794)
			(stroke
				(width 0.1)
				(type default)
			)
			(layer "B.Fab")
		)
		(fp_line
			(start 0.12065 -0.305054)
			(end 0.12065 -0.2794)
			(stroke
				(width 0.1)
				(type default)
			)
			(layer "B.Fab")
		)
		(fp_line
			(start 0.12065 -0.2794)
			(end -0.12065 -0.2794)
			(stroke
				(width 0.1)
				(type default)
			)
			(layer "B.Fab")
		)
		(fp_line
			(start 0.12065 0.2794)
			(end 0.12065 0.3048)
			(stroke
				(width 0.1)
				(type default)
			)
			(layer "B.Fab")
		)
		(fp_line
			(start 0.12065 0.3048)
			(end 0.67945 0.3048)
			(stroke
				(width 0.1)
				(type default)
			)
			(layer "B.Fab")
		)
		(fp_line
			(start 0.67945 -0.305054)
			(end 0.12065 -0.305054)
			(stroke
				(width 0.1)
				(type default)
			)
			(layer "B.Fab")
		)
		(fp_line
			(start 0.67945 0.3048)
			(end 0.67945 -0.305054)
			(stroke
				(width 0.1)
				(type default)
			)
			(layer "B.Fab")
		)
		(pad "1" smd circle
			(at 0.40005 0 180)
			(size 0 0)
			(layers "B.Cu" "B.Mask" "B.Paste")
			(net "P52V_HS1_ISTART")
		)
		(pad "2" smd circle
			(at -0.40005 0 180)
			(size 0 0)
			(layers "B.Cu" "B.Mask" "B.Paste")
			(net "P52V_HS1_VCAP")
		)
	)
	(footprint ""
		(layer "B.Cu")
		(at 341.4014 -40.7162)
		(property "Reference" "PC583"
			(at 0 0 0)
			(layer "B.SilkS")
			(hide yes)
			(effects
				(font
					(size 1.27 1.27)
				)
				(justify mirror)
			)
		)
		(property "Value" ""
			(at 0 0 0)
			(layer "B.Fab")
			(effects
				(font
					(size 1.27 1.27)
				)
				(justify mirror)
			)
		)
		(duplicate_pad_numbers_are_jumpers no)
		(fp_line
			(start -1.2954 -0.5842)
			(end -1.2954 0.5842)
			(stroke
				(width 0.1524)
				(type default)
			)
			(layer "B.SilkS")
		)
		(fp_line
			(start -1.2954 0.5842)
			(end 1.2954 0.5842)
			(stroke
				(width 0.1524)
				(type default)
			)
			(layer "B.SilkS")
		)
		(fp_line
			(start 1.2954 -0.5842)
			(end -1.2954 -0.5842)
			(stroke
				(width 0.1524)
				(type default)
			)
			(layer "B.SilkS")
		)
		(fp_line
			(start 1.2954 0.5842)
			(end 1.2954 -0.5842)
			(stroke
				(width 0.1524)
				(type default)
			)
			(layer "B.SilkS")
		)
		(fp_line
			(start -1.1938 -0.4064)
			(end -1.1938 0.4064)
			(stroke
				(width 0.1)
				(type default)
			)
			(layer "B.Fab")
		)
		(fp_line
			(start -1.1938 0.4064)
			(end -0.8636 0.4064)
			(stroke
				(width 0.1)
				(type default)
			)
			(layer "B.Fab")
		)
		(fp_line
			(start -0.8636 -0.4572)
			(end -0.8636 -0.4064)
			(stroke
				(width 0.1)
				(type default)
			)
			(layer "B.Fab")
		)
		(fp_line
			(start -0.8636 -0.4064)
			(end -1.1938 -0.4064)
			(stroke
				(width 0.1)
				(type default)
			)
			(layer "B.Fab")
		)
		(fp_line
			(start -0.8636 0.4064)
			(end -0.8636 0.4572)
			(stroke
				(width 0.1)
				(type default)
			)
			(layer "B.Fab")
		)
		(fp_line
			(start -0.8636 0.4572)
			(end 0.8636 0.4572)
			(stroke
				(width 0.1)
				(type default)
			)
			(layer "B.Fab")
		)
		(fp_line
			(start 0.8636 -0.4572)
			(end -0.8636 -0.4572)
			(stroke
				(width 0.1)
				(type default)
			)
			(layer "B.Fab")
		)
		(fp_line
			(start 0.8636 -0.4064)
			(end 0.8636 -0.4572)
			(stroke
				(width 0.1)
				(type default)
			)
			(layer "B.Fab")
		)
		(fp_line
			(start 0.8636 0.4064)
			(end 1.1938 0.4064)
			(stroke
				(width 0.1)
				(type default)
			)
			(layer "B.Fab")
		)
		(fp_line
			(start 0.8636 0.4572)
			(end 0.8636 0.4064)
			(stroke
				(width 0.1)
				(type default)
			)
			(layer "B.Fab")
		)
		(fp_line
			(start 1.1938 -0.4064)
			(end 0.8636 -0.4064)
			(stroke
				(width 0.1)
				(type default)
			)
			(layer "B.Fab")
		)
		(fp_line
			(start 1.1938 0.4064)
			(end 1.1938 -0.4064)
			(stroke
				(width 0.1)
				(type default)
			)
			(layer "B.Fab")
		)
		(pad "1" smd rect
			(at 0.7366 0 270)
			(size 0.7112 0.8128)
			(layers "B.Cu" "B.Mask" "B.Paste")
			(net "GND")
		)
		(pad "2" smd rect
			(at -0.7366 0 270)
			(size 0.7112 0.8128)
			(layers "B.Cu" "B.Mask" "B.Paste")
			(net "P52V_HS1_GATE2_R1")
		)
	)
	(footprint ""
		(layer "B.Cu")
		(at 284.2514 -63.119)
		(property "Reference" "PC83"
			(at 0 0 0)
			(layer "B.SilkS")
			(hide yes)
			(effects
				(font
					(size 1.27 1.27)
				)
				(justify mirror)
			)
		)
		(property "Value" ""
			(at 0 0 0)
			(layer "B.Fab")
			(effects
				(font
					(size 1.27 1.27)
				)
				(justify mirror)
			)
		)
		(duplicate_pad_numbers_are_jumpers no)
		(fp_line
			(start -1.2954 -0.5842)
			(end -1.2954 0.5842)
			(stroke
				(width 0.1524)
				(type default)
			)
			(layer "B.SilkS")
		)
		(fp_line
			(start -1.2954 0.5842)
			(end 1.2954 0.5842)
			(stroke
				(width 0.1524)
				(type default)
			)
			(layer "B.SilkS")
		)
		(fp_line
			(start 1.2954 -0.5842)
			(end -1.2954 -0.5842)
			(stroke
				(width 0.1524)
				(type default)
			)
			(layer "B.SilkS")
		)
		(fp_line
			(start 1.2954 0.5842)
			(end 1.2954 -0.5842)
			(stroke
				(width 0.1524)
				(type default)
			)
			(layer "B.SilkS")
		)
		(fp_line
			(start -1.1938 -0.4064)
			(end -1.1938 0.4064)
			(stroke
				(width 0.1)
				(type default)
			)
			(layer "B.Fab")
		)
		(fp_line
			(start -1.1938 0.4064)
			(end -0.8636 0.4064)
			(stroke
				(width 0.1)
				(type default)
			)
			(layer "B.Fab")
		)
		(fp_line
			(start -0.8636 -0.4572)
			(end -0.8636 -0.4064)
			(stroke
				(width 0.1)
				(type default)
			)
			(layer "B.Fab")
		)
		(fp_line
			(start -0.8636 -0.4064)
			(end -1.1938 -0.4064)
			(stroke
				(width 0.1)
				(type default)
			)
			(layer "B.Fab")
		)
		(fp_line
			(start -0.8636 0.4064)
			(end -0.8636 0.4572)
			(stroke
				(width 0.1)
				(type default)
			)
			(layer "B.Fab")
		)
		(fp_line
			(start -0.8636 0.4572)
			(end 0.8636 0.4572)
			(stroke
				(width 0.1)
				(type default)
			)
			(layer "B.Fab")
		)
		(fp_line
			(start 0.8636 -0.4572)
			(end -0.8636 -0.4572)
			(stroke
				(width 0.1)
				(type default)
			)
			(layer "B.Fab")
		)
		(fp_line
			(start 0.8636 -0.4064)
			(end 0.8636 -0.4572)
			(stroke
				(width 0.1)
				(type default)
			)
			(layer "B.Fab")
		)
		(fp_line
			(start 0.8636 0.4064)
			(end 1.1938 0.4064)
			(stroke
				(width 0.1)
				(type default)
			)
			(layer "B.Fab")
		)
		(fp_line
			(start 0.8636 0.4572)
			(end 0.8636 0.4064)
			(stroke
				(width 0.1)
				(type default)
			)
			(layer "B.Fab")
		)
		(fp_line
			(start 1.1938 -0.4064)
			(end 0.8636 -0.4064)
			(stroke
				(width 0.1)
				(type default)
			)
			(layer "B.Fab")
		)
		(fp_line
			(start 1.1938 0.4064)
			(end 1.1938 -0.4064)
			(stroke
				(width 0.1)
				(type default)
			)
			(layer "B.Fab")
		)
		(pad "1" smd rect
			(at 0.7366 0 270)
			(size 0.7112 0.8128)
			(layers "B.Cu" "B.Mask" "B.Paste")
			(net "HS1_TMR2")
		)
		(pad "2" smd rect
			(at -0.7366 0 270)
			(size 0.7112 0.8128)
			(layers "B.Cu" "B.Mask" "B.Paste")
			(net "GND_FIELD_SIGNAL")
		)
	)
	(footprint ""
		(layer "B.Cu")
		(at 169.210736 -73.279 180)
		(property "Reference" "R5885"
			(at 0 0 0)
			(layer "B.SilkS")
			(hide yes)
			(effects
				(font
					(size 1.27 1.27)
				)
				(justify mirror)
			)
		)
		(property "Value" ""
			(at 0 0 0)
			(layer "B.Fab")
			(effects
				(font
					(size 1.27 1.27)
				)
				(justify mirror)
			)
		)
		(duplicate_pad_numbers_are_jumpers no)
		(fp_line
			(start 0.7874 0.4064)
			(end 0.7874 -0.4064)
			(stroke
				(width 0.1524)
				(type default)
			)
			(layer "B.SilkS")
		)
		(fp_line
			(start 0.7874 -0.4064)
			(end -0.7874 -0.4064)
			(stroke
				(width 0.1524)
				(type default)
			)
			(layer "B.SilkS")
		)
		(fp_line
			(start -0.7874 0.4064)
			(end 0.7874 0.4064)
			(stroke
				(width 0.1524)
				(type default)
			)
			(layer "B.SilkS")
		)
		(fp_line
			(start -0.7874 -0.4064)
			(end -0.7874 0.4064)
			(stroke
				(width 0.1524)
				(type default)
			)
			(layer "B.SilkS")
		)
		(fp_line
			(start 0.67945 0.3048)
			(end 0.67945 -0.305054)
			(stroke
				(width 0.1)
				(type default)
			)
			(layer "B.Fab")
		)
		(fp_line
			(start 0.67945 -0.305054)
			(end 0.12065 -0.305054)
			(stroke
				(width 0.1)
				(type default)
			)
			(layer "B.Fab")
		)
		(fp_line
			(start 0.12065 0.3048)
			(end 0.67945 0.3048)
			(stroke
				(width 0.1)
				(type default)
			)
			(layer "B.Fab")
		)
		(fp_line
			(start 0.12065 0.2794)
			(end 0.12065 0.3048)
			(stroke
				(width 0.1)
				(type default)
			)
			(layer "B.Fab")
		)
		(fp_line
			(start 0.12065 -0.2794)
			(end -0.12065 -0.2794)
			(stroke
				(width 0.1)
				(type default)
			)
			(layer "B.Fab")
		)
		(fp_line
			(start 0.12065 -0.305054)
			(end 0.12065 -0.2794)
			(stroke
				(width 0.1)
				(type default)
			)
			(layer "B.Fab")
		)
		(fp_line
			(start -0.120396 0.3048)
			(end -0.120396 0.2794)
			(stroke
				(width 0.1)
				(type default)
			)
			(layer "B.Fab")
		)
		(fp_line
			(start -0.120396 0.2794)
			(end 0.12065 0.2794)
			(stroke
				(width 0.1)
				(type default)
			)
			(layer "B.Fab")
		)
		(fp_line
			(start -0.12065 -0.2794)
			(end -0.12065 -0.3048)
			(stroke
				(width 0.1)
				(type default)
			)
			(layer "B.Fab")
		)
		(fp_line
			(start -0.12065 -0.3048)
			(end -0.67945 -0.3048)
			(stroke
				(width 0.1)
				(type default)
			)
			(layer "B.Fab")
		)
		(fp_line
			(start -0.67945 0.3048)
			(end -0.120396 0.3048)
			(stroke
				(width 0.1)
				(type default)
			)
			(layer "B.Fab")
		)
		(fp_line
			(start -0.67945 -0.3048)
			(end -0.67945 0.3048)
			(stroke
				(width 0.1)
				(type default)
			)
			(layer "B.Fab")
		)
		(pad "1" smd circle
			(at 0.40005 0)
			(size 0 0)
			(layers "B.Cu" "B.Mask" "B.Paste")
			(net "P3V3_AUX")
		)
		(pad "2" smd circle
			(at -0.40005 0)
			(size 0 0)
			(layers "B.Cu" "B.Mask" "B.Paste")
			(net "SMB_P52V_PDB_SDA")
		)
	)
)
